FILE_TYPE = CONNECTIVITY;
{Allegro Design Entry HDL 17.2-2016 S081 (4005846) 1/11/2022}
"PAGE_NUMBER" = 20;
0"NC";
1"P1V2_AUX\g";
2"P1V2_AUX\g";
3"P2V5_AUX\g";
4"P1V2_AUX\g";
5"P1V2_AUX\g";
6"P1V2_AUX\g";
7"P0V6_DDR_VREF_AUX\g";
8"P0V6_DDR_VREF_AUX\g";
9"GND\g";
10"GND\g";
11"GND\g";
12"GND\g";
13"GND\g";
14"GND\g";
15"GND\g";
16"GND\g";
17"GND\g";
18"GND\g";
19"GND\g";
20"GND\g";
21"GND\g";
22"GND\g";
23"GND\g";
24"GND\g";
25"GND\g";
26"GND\g";
27"GND\g";
28"M_BMC_DDR4_DQ[15:0]";
29"M_BMC_DDR4_MA[13:0]";
30"M_BMC_DDR4_MA[13:0]";
31"M_BMC_DDR4_ZQU";
32"M_BMC_DDR4_MBG1";
33"M_BMC_DDR4_MCLK_C";
34"M_BMC_DDR4_ALERT_N";
35"M_BMC_DDR4_MBG1";
36"M_BMC_DDR4_MCKE";
37"M_BMC_DDR4_MODT";
38"M_BMC_DDR4_MBA1";
39"M_BMC_DDR4_MBA0";
40"M_BMC_DDR4_MBG0";
41"M_BMC_DDR4_MACT_N";
42"M_BMC_DDR4_MCS_N";
43"M_BMC_DDR4_MCAS_N";
44"M_BMC_DDR4_MWE_N";
45"M_BMC_DDR4_MA<7>";
46"M_BMC_DDR4_MA<6>";
47"M_BMC_DDR4_MA<5>";
48"M_BMC_DDR4_MA<4>";
49"M_BMC_DDR4_MA<8>";
50"M_BMC_DDR4_BG1";
51"PD_M_BMC_DDR4_PAR";
52"PD_M_BMC_DDR4_TEN";
53"M_BMC_DDR4_ALERT_N";
54"PD_M_BMC_DDR4_ZQ";
55"M_BMC_DDR4_DQS0_N";
56"M_BMC_DDR4_DQS0_P";
57"M_BMC_DDR4_DQS1_N";
58"M_BMC_DDR4_DQS1_P";
59"M_BMC_DDR4_MCLK_DN";
60"M_BMC_DDR4_MCLK_DP";
61"M_BMC_DDR4_MA<0>";
62"M_BMC_DDR4_MA<1>";
63"M_BMC_DDR4_MA<2>";
64"M_BMC_DDR4_MA<3>";
65"M_BMC_DDR4_MA<5>";
66"M_BMC_DDR4_MA<4>";
67"M_BMC_DDR4_RST_N";
68"M_BMC_DDR4_ZQU";
69"M_BMC_DDR4_BG1";
70"M_BMC_DDR4_MCAS_N";
71"M_BMC_DDR4_MWE_N";
72"M_BMC_DDR4_MCKE";
73"M_BMC_DDR4_MACT_N";
74"M_BMC_DDR4_MBG0";
75"M_BMC_DDR4_MBA0";
76"M_BMC_DDR4_MBA1";
77"M_BMC_DDR4_MRAS_N";
78"M_BMC_DDR4_MA<13>";
79"M_BMC_DDR4_MA<12>";
80"M_BMC_DDR4_MA<11>";
81"M_BMC_DDR4_MA<10>";
82"M_BMC_DDR4_MCLK_DN";
83"M_BMC_DDR4_MCLK_DP";
84"M_BMC_DDR4_MA<0>";
85"M_BMC_DDR4_MA<1>";
86"M_BMC_DDR4_MA<2>";
87"M_BMC_DDR4_MA<3>";
88"M_BMC_DDR4_MA<9>";
89"M_BMC_DDR4_MODT";
90"M_BMC_DDR4_MRAS_N";
91"M_BMC_DDR4_MCS_N";
92"M_BMC_DDR4_MDM0";
93"M_BMC_DDR4_MDM1";
94"M_BMC_DDR4_MA<13>";
95"M_BMC_DDR4_MA<10>";
96"M_BMC_DDR4_MA<6>";
97"M_BMC_DDR4_MA<11>";
98"M_BMC_DDR4_MA<12>";
99"M_BMC_DDR4_MA<7>";
100"M_BMC_DDR4_MA<8>";
101"M_BMC_DDR4_MA<9>";
102"M_BMC_DDR4_DQ<0>";
103"M_BMC_DDR4_DQ<1>";
104"M_BMC_DDR4_DQ<2>";
105"M_BMC_DDR4_DQ<3>";
106"M_BMC_DDR4_DQ<4>";
107"M_BMC_DDR4_DQ<5>";
108"M_BMC_DDR4_DQ<6>";
109"M_BMC_DDR4_DQ<7>";
110"M_BMC_DDR4_DQ<8>";
111"M_BMC_DDR4_DQ<9>";
112"M_BMC_DDR4_DQ<10>";
113"M_BMC_DDR4_DQ<11>";
114"M_BMC_DDR4_DQ<12>";
115"M_BMC_DDR4_DQ<13>";
116"M_BMC_DDR4_DQ<14>";
117"M_BMC_DDR4_DQ<15>";
%"Q_CAP"
"2","(3700,-1050)","0","pure_quanta","I106";
;
VALUE"0.22UF"
PACK_TYPE"0402"
SEC_TYPE"0402"
CDS_LIB"pure_quanta"
VOLTAGE"16V"
TOLERANCE"10%"
PART_NUMBER"CH4223K1B00"
MATERIAL"X7R"
LOCATION"C12"
SEC"1";
"A"
$PN"1"33;
"B"
$PN"2"27;
%"Q_CAP"
"2","(3700,-750)","0","pure_quanta","I107";
;
PART_NUMBER"CH4223K1B00"
VALUE"0.22UF"
MATERIAL"EMPTY"
PACK_TYPE"0402"
CDS_LIB"pure_quanta"
SEC_TYPE"0402"
VOLTAGE"16V"
TOLERANCE"10%"
LOCATION"C229"
SEC"1";
"A"
$PN"1"33;
"B"
$PN"2"6;
%"UNIVERSAL_GND"
"1","(4000,-1300)","0","logical_power","I108";
;
HDL_POWER"GND"
CDS_LIB"logical_power";
"A"27;
%"UNIVERSAL_GND"
"1","(3275,-50)","0","logical_power","I109";
;
HDL_POWER"GND"
CDS_LIB"logical_power";
"A"26;
%"UNIVERSAL_POWER"
"1","(4175,-475)","0","logical_power","I110";
;
HDL_POWER"P1V2_AUX"
CDS_LIB"logical_power";
"A"6;
%"Q_RES"
"1","(4325,175)","0","pure_quanta","I111";
;
PART_NUMBER"CS24702FB06"
PACK_TYPE"0402LF"
MATERIAL"CHIP"
WATTAGE"1/16W"
TOLERANCE"1%"
VALUE"4.7K"
SEC_TYPE"0402LF"
CDS_LIB"pure_quanta"
LOCATION"R9"
SEC"1";
"B"
$PN"2"5;
"A"
$PN"1"34;
%"UNIVERSAL_GND"
"1","(4975,100)","0","logical_power","I112";
;
HDL_POWER"GND"
CDS_LIB"logical_power";
"A"25;
%"Q_CAP"
"1","(4975,325)","0","pure_quanta","I113";
;
VOLTAGE"6.3V"
PACK_TYPE"C0402"
TOLERANCE"20%"
VALUE"10UF"
PART_NUMBER"CH6101MEB01"
MATERIAL"X6S"
SEC_TYPE"C0402"
CDS_LIB"pure_quanta"
LOCATION"C16"
SEC"1";
"B"
$PN"2"25;
"A"
$PN"1"5;
%"Q_RES"
"1","(3650,425)","0","pure_quanta","I114";
;
MATERIAL"EMPTY"
VALUE"120"
PART_NUMBER"CS11202FB02"
PACK_TYPE"0402LF"
WATTAGE"1/16W"
TOLERANCE"1%"
CDS_LIB"pure_quanta"
LOCATION"R350"
$SEC"1"
CDS_SEC"1";
"B"
$PN"2"35;
"A"
$PN"1"26;
%"Q_RES"
"1","(4325,425)","0","pure_quanta","I115";
;
MATERIAL"EMPTY"
VALUE"120"
PART_NUMBER"CS11202FB02"
PACK_TYPE"0402LF"
WATTAGE"1/16W"
TOLERANCE"1%"
CDS_LIB"pure_quanta"
LOCATION"R375"
$SEC"1"
CDS_SEC"1";
"B"
$PN"2"5;
"A"
$PN"1"35;
%"Q_RES"
"1","(3650,575)","0","pure_quanta","I116";
;
VALUE"120"
MATERIAL"CHIP"
PART_NUMBER"CS11202FB02"
PACK_TYPE"0402LF"
WATTAGE"1/16W"
TOLERANCE"1%"
CDS_LIB"pure_quanta"
LOCATION"R349"
$SEC"1"
CDS_SEC"1";
"B"
$PN"2"36;
"A"
$PN"1"26;
%"Q_RES"
"1","(3650,875)","0","pure_quanta","I117";
;
VALUE"120"
MATERIAL"CHIP"
PART_NUMBER"CS11202FB02"
PACK_TYPE"0402LF"
WATTAGE"1/16W"
TOLERANCE"1%"
CDS_LIB"pure_quanta"
LOCATION"R347"
$SEC"1"
CDS_SEC"1";
"B"
$PN"2"38;
"A"
$PN"1"26;
%"Q_RES"
"1","(3650,725)","0","pure_quanta","I118";
;
MATERIAL"CHIP"
VALUE"120"
PART_NUMBER"CS11202FB02"
PACK_TYPE"0402LF"
WATTAGE"1/16W"
TOLERANCE"1%"
CDS_LIB"pure_quanta"
LOCATION"R348"
$SEC"1"
CDS_SEC"1";
"B"
$PN"2"37;
"A"
$PN"1"26;
%"Q_RES"
"1","(3650,1175)","0","pure_quanta","I119";
;
VALUE"120"
MATERIAL"CHIP"
PART_NUMBER"CS11202FB02"
PACK_TYPE"0402LF"
WATTAGE"1/16W"
TOLERANCE"1%"
CDS_LIB"pure_quanta"
LOCATION"R345"
$SEC"1"
CDS_SEC"1";
"B"
$PN"2"40;
"A"
$PN"1"26;
%"Q_RES"
"1","(3650,1025)","0","pure_quanta","I120";
;
VALUE"120"
MATERIAL"CHIP"
PART_NUMBER"CS11202FB02"
PACK_TYPE"0402LF"
WATTAGE"1/16W"
TOLERANCE"1%"
CDS_LIB"pure_quanta"
LOCATION"R346"
$SEC"1"
CDS_SEC"1";
"B"
$PN"2"39;
"A"
$PN"1"26;
%"Q_RES"
"1","(3650,1325)","0","pure_quanta","I121";
;
VALUE"120"
MATERIAL"CHIP"
PART_NUMBER"CS11202FB02"
PACK_TYPE"0402LF"
WATTAGE"1/16W"
TOLERANCE"1%"
CDS_LIB"pure_quanta"
LOCATION"R344"
$SEC"1"
CDS_SEC"1";
"B"
$PN"2"41;
"A"
$PN"1"26;
%"Q_RES"
"1","(3650,1625)","0","pure_quanta","I122";
;
MATERIAL"CHIP"
VALUE"120"
PART_NUMBER"CS11202FB02"
PACK_TYPE"0402LF"
WATTAGE"1/16W"
TOLERANCE"1%"
CDS_LIB"pure_quanta"
LOCATION"R342"
$SEC"1"
CDS_SEC"1";
"B"
$PN"2"77;
"A"
$PN"1"26;
%"Q_RES"
"1","(3650,1475)","0","pure_quanta","I123";
;
VALUE"120"
MATERIAL"CHIP"
PART_NUMBER"CS11202FB02"
PACK_TYPE"0402LF"
WATTAGE"1/16W"
TOLERANCE"1%"
CDS_LIB"pure_quanta"
LOCATION"R343"
$SEC"1"
CDS_SEC"1";
"B"
$PN"2"42;
"A"
$PN"1"26;
%"Q_RES"
"1","(3650,1925)","0","pure_quanta","I124";
;
MATERIAL"CHIP"
VALUE"120"
PART_NUMBER"CS11202FB02"
PACK_TYPE"0402LF"
WATTAGE"1/16W"
TOLERANCE"1%"
CDS_LIB"pure_quanta"
LOCATION"R340"
$SEC"1"
CDS_SEC"1";
"B"
$PN"2"44;
"A"
$PN"1"26;
%"Q_RES"
"1","(3650,1775)","0","pure_quanta","I125";
;
MATERIAL"CHIP"
VALUE"120"
PART_NUMBER"CS11202FB02"
PACK_TYPE"0402LF"
WATTAGE"1/16W"
TOLERANCE"1%"
CDS_LIB"pure_quanta"
LOCATION"R341"
$SEC"1"
CDS_SEC"1";
"B"
$PN"2"43;
"A"
$PN"1"26;
%"UNIVERSAL_GND"
"1","(3225,2425)","0","logical_power","I126";
;
HDL_POWER"GND"
CDS_LIB"logical_power";
"A"24;
%"Q_RES"
"1","(4325,575)","0","pure_quanta","I127";
;
VALUE"120"
MATERIAL"CHIP"
PART_NUMBER"CS11202FB02"
PACK_TYPE"0402LF"
WATTAGE"1/16W"
TOLERANCE"1%"
CDS_LIB"pure_quanta"
LOCATION"R374"
$SEC"1"
CDS_SEC"1";
"B"
$PN"2"5;
"A"
$PN"1"36;
%"Q_RES"
"1","(4325,725)","0","pure_quanta","I128";
;
MATERIAL"CHIP"
VALUE"120"
PART_NUMBER"CS11202FB02"
PACK_TYPE"0402LF"
WATTAGE"1/16W"
TOLERANCE"1%"
CDS_LIB"pure_quanta"
LOCATION"R373"
$SEC"1"
CDS_SEC"1";
"B"
$PN"2"5;
"A"
$PN"1"37;
%"Q_RES"
"1","(4325,875)","0","pure_quanta","I129";
;
MATERIAL"CHIP"
VALUE"120"
PART_NUMBER"CS11202FB02"
PACK_TYPE"0402LF"
WATTAGE"1/16W"
TOLERANCE"1%"
CDS_LIB"pure_quanta"
LOCATION"R372"
$SEC"1"
CDS_SEC"1";
"B"
$PN"2"5;
"A"
$PN"1"38;
%"Q_RES"
"1","(-2425,-1050)","0","pure_quanta","I13";
;
PART_NUMBER"CS00002JB13"
PACK_TYPE"0402LF"
WATTAGE"1/16W"
TOLERANCE"5%"
MATERIAL"CHIP"
VALUE"0"
SEC_TYPE"0402LF"
CDS_LIB"pure_quanta"
LOCATION"R2"
SEC"1";
"B"
$PN"2"22;
"A"
$PN"1"50;
%"Q_RES"
"1","(4325,1025)","0","pure_quanta","I130";
;
MATERIAL"CHIP"
VALUE"120"
PART_NUMBER"CS11202FB02"
PACK_TYPE"0402LF"
WATTAGE"1/16W"
TOLERANCE"1%"
CDS_LIB"pure_quanta"
LOCATION"R371"
$SEC"1"
CDS_SEC"1";
"B"
$PN"2"5;
"A"
$PN"1"39;
%"Q_RES"
"1","(4325,1175)","0","pure_quanta","I131";
;
MATERIAL"CHIP"
VALUE"120"
PART_NUMBER"CS11202FB02"
PACK_TYPE"0402LF"
WATTAGE"1/16W"
TOLERANCE"1%"
CDS_LIB"pure_quanta"
LOCATION"R370"
$SEC"1"
CDS_SEC"1";
"B"
$PN"2"5;
"A"
$PN"1"40;
%"Q_RES"
"1","(4325,1325)","0","pure_quanta","I132";
;
MATERIAL"CHIP"
VALUE"120"
PART_NUMBER"CS11202FB02"
PACK_TYPE"0402LF"
WATTAGE"1/16W"
TOLERANCE"1%"
CDS_LIB"pure_quanta"
LOCATION"R369"
$SEC"1"
CDS_SEC"1";
"B"
$PN"2"5;
"A"
$PN"1"41;
%"UNIVERSAL_GND"
"1","(4975,850)","0","logical_power","I133";
;
HDL_POWER"GND"
CDS_LIB"logical_power";
"A"23;
%"Q_CAP"
"1","(4975,1075)","0","pure_quanta","I134";
;
VOLTAGE"6.3V"
PACK_TYPE"C0402"
TOLERANCE"20%"
VALUE"10UF"
MATERIAL"X6S"
SEC_TYPE"C0402"
CDS_LIB"pure_quanta"
PART_NUMBER"CH6101MEB01"
LOCATION"C15"
SEC"1";
"B"
$PN"2"23;
"A"
$PN"1"5;
%"Q_RES"
"1","(4325,1475)","0","pure_quanta","I135";
;
MATERIAL"CHIP"
VALUE"120"
PART_NUMBER"CS11202FB02"
PACK_TYPE"0402LF"
WATTAGE"1/16W"
TOLERANCE"1%"
CDS_LIB"pure_quanta"
LOCATION"R368"
$SEC"1"
CDS_SEC"1";
"B"
$PN"2"5;
"A"
$PN"1"42;
%"Q_RES"
"1","(4325,1625)","0","pure_quanta","I136";
;
MATERIAL"CHIP"
VALUE"120"
PART_NUMBER"CS11202FB02"
PACK_TYPE"0402LF"
WATTAGE"1/16W"
TOLERANCE"1%"
CDS_LIB"pure_quanta"
LOCATION"R367"
$SEC"1"
CDS_SEC"1";
"B"
$PN"2"5;
"A"
$PN"1"77;
%"Q_RES"
"1","(4325,1775)","0","pure_quanta","I137";
;
MATERIAL"CHIP"
VALUE"120"
PART_NUMBER"CS11202FB02"
PACK_TYPE"0402LF"
WATTAGE"1/16W"
TOLERANCE"1%"
CDS_LIB"pure_quanta"
LOCATION"R366"
$SEC"1"
CDS_SEC"1";
"B"
$PN"2"5;
"A"
$PN"1"43;
%"Q_RES"
"1","(4325,1925)","0","pure_quanta","I138";
;
PART_NUMBER"CS11202FB02"
PACK_TYPE"0402LF"
MATERIAL"CHIP"
WATTAGE"1/16W"
TOLERANCE"1%"
VALUE"120"
CDS_LIB"pure_quanta"
LOCATION"R365"
$SEC"1"
CDS_SEC"1";
"B"
$PN"2"5;
"A"
$PN"1"44;
%"UNIVERSAL_POWER"
"1","(4775,2125)","0","logical_power","I139";
;
HDL_POWER"P1V2_AUX"
CDS_LIB"logical_power";
"A"5;
%"Q_RES"
"1","(-2425,-850)","0","pure_quanta","I14";
;
PART_NUMBER"CS00002JB13"
VALUE"0"
MATERIAL"EMPTY"
PACK_TYPE"0402LF"
WATTAGE"1/16W"
TOLERANCE"5%"
SEC_TYPE"0402LF"
CDS_LIB"pure_quanta"
LOCATION"R1"
SEC"1";
"B"
$PN"2"32;
"A"
$PN"1"50;
%"UNIVERSAL_POWER"
"1","(1150,2875)","0","logical_power","I140";
;
HDL_POWER"P0V6_DDR_VREF_AUX"
CDS_LIB"logical_power";
"A"7;
%"Q_RES"
"2","(1400,2775)","0","pure_quanta","I141";
;
PACK_TYPE"0402LF"
MATERIAL"CHIP"
WATTAGE"1/16W"
TOLERANCE"1%"
VALUE"1K"
PART_NUMBER"CS21002FB06"
SEC_TYPE"0402LF"
CDS_LIB"pure_quanta"
LOCATION"R4"
SEC"1";
"A"
$PN"1"51;
"B"
$PN"2"10;
%"Q_RES"
"2","(1750,2775)","0","pure_quanta","I142";
;
PACK_TYPE"0402LF"
MATERIAL"CHIP"
WATTAGE"1/16W"
TOLERANCE"1%"
VALUE"1K"
PART_NUMBER"CS21002FB06"
CDS_LIB"pure_quanta"
SEC_TYPE"0402LF"
LOCATION"R5"
SEC"1";
"A"
$PN"1"52;
"B"
$PN"2"10;
%"Q_RES"
"2","(2075,2775)","0","pure_quanta","I143";
;
PACK_TYPE"0402LF"
MATERIAL"CHIP"
VALUE"240"
TOLERANCE"1%"
WATTAGE"1/16W"
PART_NUMBER"CS12402FB01"
CDS_LIB"pure_quanta"
SEC_TYPE"0402LF"
LOCATION"R6"
SEC"1";
"A"
$PN"1"54;
"B"
$PN"2"9;
%"TAP"
"1","(2675,2775)","2","standard","I144";
;
HDL_TAP"TRUE"
BODY_TYPE"PLUMBING"
CDS_LIB"standard";
"B \NAC \NWC"30;
"S \NAC"
BN"13"78;
%"TAP"
"1","(2675,2925)","2","standard","I145";
;
HDL_TAP"TRUE"
BODY_TYPE"PLUMBING"
CDS_LIB"standard";
"B \NAC \NWC"30;
"S \NAC"
BN"12"79;
%"TAP"
"1","(2675,3375)","2","standard","I146";
;
HDL_TAP"TRUE"
BODY_TYPE"PLUMBING"
CDS_LIB"standard";
"B \NAC \NWC"30;
"S \NAC"
BN"9"88;
%"TAP"
"1","(2675,3225)","2","standard","I147";
;
HDL_TAP"TRUE"
BODY_TYPE"PLUMBING"
CDS_LIB"standard";
"B \NAC \NWC"30;
"S \NAC"
BN"10"81;
%"TAP"
"1","(2675,3075)","2","standard","I148";
;
HDL_TAP"TRUE"
BODY_TYPE"PLUMBING"
CDS_LIB"standard";
"B \NAC \NWC"30;
"S \NAC"
BN"11"80;
%"TAP"
"1","(2675,3825)","2","standard","I149";
;
HDL_TAP"TRUE"
BODY_TYPE"PLUMBING"
CDS_LIB"standard";
"B \NAC \NWC"30;
"S \NAC"
BN"6"46;
%"UNIVERSAL_GND"
"1","(-2025,-1200)","0","logical_power","I15";
;
HDL_POWER"GND"
CDS_LIB"logical_power";
"A"22;
%"TAP"
"1","(2675,3525)","2","standard","I150";
;
HDL_TAP"TRUE"
BODY_TYPE"PLUMBING"
CDS_LIB"standard";
"B \NAC \NWC"30;
"S \NAC"
BN"8"49;
%"TAP"
"1","(2675,3675)","2","standard","I151";
;
HDL_TAP"TRUE"
BODY_TYPE"PLUMBING"
CDS_LIB"standard";
"B \NAC \NWC"30;
"S \NAC"
BN"7"45;
%"TAP"
"1","(2675,3975)","2","standard","I152";
;
HDL_TAP"TRUE"
BODY_TYPE"PLUMBING"
CDS_LIB"standard";
"B \NAC \NWC"30;
"S \NAC"
BN"5"47;
%"TAP"
"1","(2675,4425)","2","standard","I153";
;
HDL_TAP"TRUE"
BODY_TYPE"PLUMBING"
CDS_LIB"standard";
"B \NAC \NWC"30;
"S \NAC"
BN"2"86;
%"TAP"
"1","(2675,4275)","2","standard","I154";
;
HDL_TAP"TRUE"
BODY_TYPE"PLUMBING"
CDS_LIB"standard";
"B \NAC \NWC"30;
"S \NAC"
BN"3"87;
%"TAP"
"1","(2675,4125)","2","standard","I155";
;
HDL_TAP"TRUE"
BODY_TYPE"PLUMBING"
CDS_LIB"standard";
"B \NAC \NWC"30;
"S \NAC"
BN"4"48;
%"TAP"
"1","(2675,4575)","2","standard","I157";
;
HDL_TAP"TRUE"
BODY_TYPE"PLUMBING"
CDS_LIB"standard";
"B \NAC \NWC"30;
"S \NAC"
BN"1"85;
%"TAP"
"1","(2675,4725)","2","standard","I158";
;
HDL_TAP"TRUE"
BODY_TYPE"PLUMBING"
CDS_LIB"standard";
"B \NAC \NWC"30;
"S \NAC"
BN"0"84;
%"Q_RES"
"1","(3600,2700)","0","pure_quanta","I159";
;
MATERIAL"CHIP"
VALUE"120"
PART_NUMBER"CS11202FB02"
PACK_TYPE"0402LF"
WATTAGE"1/16W"
TOLERANCE"1%"
CDS_LIB"pure_quanta"
LOCATION"R339"
$SEC"1"
CDS_SEC"1";
"B"
$PN"2"78;
"A"
$PN"1"24;
%"UNIVERSAL_GND"
"1","(-1950,-600)","0","logical_power","I16";
;
HDL_POWER"GND"
CDS_LIB"logical_power";
"A"21;
%"Q_RES"
"1","(3600,2850)","0","pure_quanta","I160";
;
MATERIAL"CHIP"
VALUE"120"
PART_NUMBER"CS11202FB02"
PACK_TYPE"0402LF"
WATTAGE"1/16W"
TOLERANCE"1%"
CDS_LIB"pure_quanta"
LOCATION"R338"
$SEC"1"
CDS_SEC"1";
"B"
$PN"2"79;
"A"
$PN"1"24;
%"Q_RES"
"1","(3600,3000)","0","pure_quanta","I161";
;
VALUE"120"
MATERIAL"CHIP"
PART_NUMBER"CS11202FB02"
PACK_TYPE"0402LF"
WATTAGE"1/16W"
TOLERANCE"1%"
CDS_LIB"pure_quanta"
LOCATION"R337"
$SEC"1"
CDS_SEC"1";
"B"
$PN"2"80;
"A"
$PN"1"24;
%"Q_RES"
"1","(3600,3150)","0","pure_quanta","I162";
;
MATERIAL"CHIP"
VALUE"120"
PART_NUMBER"CS11202FB02"
PACK_TYPE"0402LF"
WATTAGE"1/16W"
TOLERANCE"1%"
CDS_LIB"pure_quanta"
LOCATION"R336"
$SEC"1"
CDS_SEC"1";
"B"
$PN"2"81;
"A"
$PN"1"24;
%"Q_RES"
"1","(3600,3300)","0","pure_quanta","I163";
;
MATERIAL"CHIP"
VALUE"120"
PART_NUMBER"CS11202FB02"
PACK_TYPE"0402LF"
WATTAGE"1/16W"
TOLERANCE"1%"
CDS_LIB"pure_quanta"
LOCATION"R335"
$SEC"1"
CDS_SEC"1";
"B"
$PN"2"88;
"A"
$PN"1"24;
%"Q_RES"
"1","(3600,3450)","0","pure_quanta","I164";
;
MATERIAL"CHIP"
VALUE"120"
PART_NUMBER"CS11202FB02"
PACK_TYPE"0402LF"
WATTAGE"1/16W"
TOLERANCE"1%"
CDS_LIB"pure_quanta"
LOCATION"R334"
$SEC"1"
CDS_SEC"1";
"B"
$PN"2"49;
"A"
$PN"1"24;
%"Q_RES"
"1","(4275,2700)","0","pure_quanta","I165";
;
PACK_TYPE"0402LF"
TOLERANCE"1%"
VALUE"120"
WATTAGE"1/16W"
PART_NUMBER"CS11202FB02"
MATERIAL"CHIP"
CDS_LIB"pure_quanta"
LOCATION"R364"
$SEC"1"
CDS_SEC"1";
"B"
$PN"2"4;
"A"
$PN"1"78;
%"Q_RES"
"1","(4275,2850)","0","pure_quanta","I166";
;
VALUE"120"
MATERIAL"CHIP"
PART_NUMBER"CS11202FB02"
PACK_TYPE"0402LF"
WATTAGE"1/16W"
TOLERANCE"1%"
CDS_LIB"pure_quanta"
LOCATION"R363"
$SEC"1"
CDS_SEC"1";
"B"
$PN"2"4;
"A"
$PN"1"79;
%"Q_RES"
"1","(4275,3150)","0","pure_quanta","I167";
;
VALUE"120"
MATERIAL"CHIP"
PART_NUMBER"CS11202FB02"
PACK_TYPE"0402LF"
WATTAGE"1/16W"
TOLERANCE"1%"
CDS_LIB"pure_quanta"
LOCATION"R361"
$SEC"1"
CDS_SEC"1";
"B"
$PN"2"4;
"A"
$PN"1"81;
%"Q_RES"
"1","(4275,3000)","0","pure_quanta","I168";
;
MATERIAL"CHIP"
VALUE"120"
PART_NUMBER"CS11202FB02"
PACK_TYPE"0402LF"
WATTAGE"1/16W"
TOLERANCE"1%"
CDS_LIB"pure_quanta"
LOCATION"R362"
$SEC"1"
CDS_SEC"1";
"B"
$PN"2"4;
"A"
$PN"1"80;
%"Q_RES"
"1","(4275,3300)","0","pure_quanta","I169";
;
MATERIAL"CHIP"
VALUE"120"
PART_NUMBER"CS11202FB02"
PACK_TYPE"0402LF"
WATTAGE"1/16W"
TOLERANCE"1%"
CDS_LIB"pure_quanta"
LOCATION"R360"
$SEC"1"
CDS_SEC"1";
"B"
$PN"2"4;
"A"
$PN"1"88;
%"Q_RES"
"1","(-2350,-450)","0","pure_quanta","I17";
;
VALUE"0"
TOLERANCE"5%"
MATERIAL"CHIP"
PACK_TYPE"0402LF"
WATTAGE"1/16W"
PART_NUMBER"CS00002JB13"
SEC_TYPE"0402LF"
CDS_LIB"pure_quanta"
LOCATION"R3"
SEC"1";
"B"
$PN"2"21;
"A"
$PN"1"31;
%"Q_RES"
"1","(4275,3450)","0","pure_quanta","I170";
;
MATERIAL"CHIP"
VALUE"120"
PART_NUMBER"CS11202FB02"
PACK_TYPE"0402LF"
WATTAGE"1/16W"
TOLERANCE"1%"
CDS_LIB"pure_quanta"
LOCATION"R359"
$SEC"1"
CDS_SEC"1";
"B"
$PN"2"4;
"A"
$PN"1"49;
%"Q_RES"
"1","(3600,3750)","0","pure_quanta","I171";
;
MATERIAL"CHIP"
VALUE"120"
PART_NUMBER"CS11202FB02"
PACK_TYPE"0402LF"
WATTAGE"1/16W"
TOLERANCE"1%"
CDS_LIB"pure_quanta"
LOCATION"R332"
$SEC"1"
CDS_SEC"1";
"B"
$PN"2"46;
"A"
$PN"1"24;
%"Q_RES"
"1","(3600,3600)","0","pure_quanta","I172";
;
MATERIAL"CHIP"
VALUE"120"
PART_NUMBER"CS11202FB02"
PACK_TYPE"0402LF"
WATTAGE"1/16W"
TOLERANCE"1%"
CDS_LIB"pure_quanta"
LOCATION"R333"
$SEC"1"
CDS_SEC"1";
"B"
$PN"2"45;
"A"
$PN"1"24;
%"Q_RES"
"1","(3600,3900)","0","pure_quanta","I173";
;
MATERIAL"CHIP"
VALUE"120"
PART_NUMBER"CS11202FB02"
PACK_TYPE"0402LF"
WATTAGE"1/16W"
TOLERANCE"1%"
CDS_LIB"pure_quanta"
LOCATION"R331"
$SEC"1"
CDS_SEC"1";
"B"
$PN"2"47;
"A"
$PN"1"24;
%"Q_RES"
"1","(3600,4050)","0","pure_quanta","I174";
;
VALUE"120"
MATERIAL"CHIP"
PART_NUMBER"CS11202FB02"
PACK_TYPE"0402LF"
WATTAGE"1/16W"
TOLERANCE"1%"
CDS_LIB"pure_quanta"
LOCATION"R330"
$SEC"1"
CDS_SEC"1";
"B"
$PN"2"48;
"A"
$PN"1"24;
%"Q_RES"
"1","(3600,4200)","0","pure_quanta","I175";
;
MATERIAL"CHIP"
VALUE"120"
PART_NUMBER"CS11202FB02"
PACK_TYPE"0402LF"
WATTAGE"1/16W"
TOLERANCE"1%"
CDS_LIB"pure_quanta"
LOCATION"R329"
$SEC"1"
CDS_SEC"1";
"B"
$PN"2"87;
"A"
$PN"1"24;
%"Q_RES"
"1","(3600,4350)","0","pure_quanta","I176";
;
MATERIAL"CHIP"
VALUE"120"
PART_NUMBER"CS11202FB02"
PACK_TYPE"0402LF"
WATTAGE"1/16W"
TOLERANCE"1%"
CDS_LIB"pure_quanta"
LOCATION"R328"
$SEC"1"
CDS_SEC"1";
"B"
$PN"2"86;
"A"
$PN"1"24;
%"Q_RES"
"1","(3600,4500)","0","pure_quanta","I177";
;
MATERIAL"CHIP"
VALUE"120"
PART_NUMBER"CS11202FB02"
PACK_TYPE"0402LF"
WATTAGE"1/16W"
TOLERANCE"1%"
CDS_LIB"pure_quanta"
LOCATION"R327"
$SEC"1"
CDS_SEC"1";
"B"
$PN"2"85;
"A"
$PN"1"24;
%"Q_RES"
"1","(4275,3600)","0","pure_quanta","I178";
;
MATERIAL"CHIP"
VALUE"120"
PART_NUMBER"CS11202FB02"
PACK_TYPE"0402LF"
WATTAGE"1/16W"
TOLERANCE"1%"
CDS_LIB"pure_quanta"
LOCATION"R358"
$SEC"1"
CDS_SEC"1";
"B"
$PN"2"4;
"A"
$PN"1"45;
%"Q_RES"
"1","(4275,3750)","0","pure_quanta","I179";
;
MATERIAL"CHIP"
VALUE"120"
PART_NUMBER"CS11202FB02"
PACK_TYPE"0402LF"
WATTAGE"1/16W"
TOLERANCE"1%"
CDS_LIB"pure_quanta"
LOCATION"R357"
$SEC"1"
CDS_SEC"1";
"B"
$PN"2"4;
"A"
$PN"1"46;
%"Q_RES"
"1","(4275,3900)","0","pure_quanta","I180";
;
MATERIAL"CHIP"
VALUE"120"
PART_NUMBER"CS11202FB02"
PACK_TYPE"0402LF"
WATTAGE"1/16W"
TOLERANCE"1%"
CDS_LIB"pure_quanta"
LOCATION"R356"
$SEC"1"
CDS_SEC"1";
"B"
$PN"2"4;
"A"
$PN"1"47;
%"Q_RES"
"1","(4275,4200)","0","pure_quanta","I181";
;
MATERIAL"CHIP"
VALUE"120"
PART_NUMBER"CS11202FB02"
PACK_TYPE"0402LF"
WATTAGE"1/16W"
TOLERANCE"1%"
CDS_LIB"pure_quanta"
LOCATION"R354"
$SEC"1"
CDS_SEC"1";
"B"
$PN"2"4;
"A"
$PN"1"87;
%"Q_RES"
"1","(4275,4050)","0","pure_quanta","I182";
;
MATERIAL"CHIP"
VALUE"120"
PART_NUMBER"CS11202FB02"
PACK_TYPE"0402LF"
WATTAGE"1/16W"
TOLERANCE"1%"
CDS_LIB"pure_quanta"
LOCATION"R355"
$SEC"1"
CDS_SEC"1";
"B"
$PN"2"4;
"A"
$PN"1"48;
%"Q_RES"
"1","(4275,4350)","0","pure_quanta","I183";
;
MATERIAL"CHIP"
VALUE"120"
PART_NUMBER"CS11202FB02"
PACK_TYPE"0402LF"
WATTAGE"1/16W"
TOLERANCE"1%"
CDS_LIB"pure_quanta"
LOCATION"R353"
$SEC"1"
CDS_SEC"1";
"B"
$PN"2"4;
"A"
$PN"1"86;
%"Q_RES"
"1","(4275,4500)","0","pure_quanta","I184";
;
MATERIAL"CHIP"
VALUE"120"
PART_NUMBER"CS11202FB02"
PACK_TYPE"0402LF"
WATTAGE"1/16W"
TOLERANCE"1%"
CDS_LIB"pure_quanta"
LOCATION"R352"
$SEC"1"
CDS_SEC"1";
"B"
$PN"2"4;
"A"
$PN"1"85;
%"UNIVERSAL_GND"
"1","(4875,3475)","0","logical_power","I185";
;
HDL_POWER"GND"
CDS_LIB"logical_power";
"A"20;
%"Q_CAP"
"1","(4875,3650)","0","pure_quanta","I186";
;
PACK_TYPE"0402"
VOLTAGE"25V"
TOLERANCE"10%"
VALUE"0.1UF"
PART_NUMBER"CH4104K1B00"
MATERIAL"X7R"
CDS_LIB"pure_quanta"
SEC_TYPE"0402"
LOCATION"C13"
SEC"1";
"B"
$PN"2"20;
"A"
$PN"1"4;
%"Q_CAP"
"1","(4950,3975)","0","pure_quanta","I187";
;
PACK_TYPE"0402"
VOLTAGE"25V"
TOLERANCE"10%"
VALUE"0.1UF"
MATERIAL"X7R"
SEC_TYPE"0402"
CDS_LIB"pure_quanta"
PART_NUMBER"CH4104K1B00"
LOCATION"C14"
SEC"1";
"B"
$PN"2"19;
"A"
$PN"1"4;
%"UNIVERSAL_GND"
"1","(4950,3800)","0","logical_power","I188";
;
HDL_POWER"GND"
CDS_LIB"logical_power";
"A"19;
%"UNIVERSAL_GND"
"1","(5025,4100)","0","logical_power","I189";
;
HDL_POWER"GND"
CDS_LIB"logical_power";
"A"18;
%"Q_CAP"
"1","(-3050,1300)","0","pure_quanta","I19";
;
VOLTAGE"25V"
VALUE"0.1UF"
TOLERANCE"10%"
MATERIAL"X7R"
PACK_TYPE"0402"
SEC_TYPE"0402"
CDS_LIB"pure_quanta"
PART_NUMBER"CH4104K1B00"
LOCATION"C6"
SEC"1";
"B"
$PN"2"16;
"A"
$PN"1"3;
%"Q_CAP"
"1","(5025,4275)","0","pure_quanta","I190";
;
PACK_TYPE"0402"
VOLTAGE"25V"
TOLERANCE"10%"
VALUE"0.1UF"
MATERIAL"X7R"
CDS_LIB"pure_quanta"
SEC_TYPE"0402"
PART_NUMBER"CH4104K1B00"
LOCATION"C17"
SEC"1";
"B"
$PN"2"18;
"A"
$PN"1"4;
%"UNIVERSAL_GND"
"1","(5175,4425)","0","logical_power","I191";
;
HDL_POWER"GND"
CDS_LIB"logical_power";
"A"17;
%"Q_CAP"
"1","(5175,4600)","0","pure_quanta","I192";
;
PACK_TYPE"0402"
VOLTAGE"25V"
TOLERANCE"10%"
VALUE"0.1UF"
MATERIAL"X7R"
CDS_LIB"pure_quanta"
SEC_TYPE"0402"
PART_NUMBER"CH4104K1B00"
LOCATION"C18"
SEC"1";
"B"
$PN"2"17;
"A"
$PN"1"4;
%"Q_RES"
"1","(3600,4650)","0","pure_quanta","I193";
;
MATERIAL"CHIP"
VALUE"120"
PART_NUMBER"CS11202FB02"
PACK_TYPE"0402LF"
WATTAGE"1/16W"
TOLERANCE"1%"
CDS_LIB"pure_quanta"
LOCATION"R326"
$SEC"1"
CDS_SEC"1";
"B"
$PN"2"84;
"A"
$PN"1"24;
%"Q_RES"
"1","(4275,4650)","0","pure_quanta","I194";
;
PART_NUMBER"CS11202FB02"
PACK_TYPE"0402LF"
MATERIAL"CHIP"
WATTAGE"1/16W"
TOLERANCE"1%"
VALUE"120"
CDS_LIB"pure_quanta"
LOCATION"R351"
$SEC"1"
CDS_SEC"1";
"B"
$PN"2"4;
"A"
$PN"1"84;
%"UNIVERSAL_POWER"
"1","(4725,4850)","0","logical_power","I195";
;
HDL_POWER"P1V2_AUX"
CDS_LIB"logical_power";
"A"4;
%"K4A8G165WCBCTD"
"1","(-1075,3100)","0","pure_quanta","I196";
;
MATERIAL"IC"
PART_NUMBER"AKD5FGUT502"
VALUE"K4A8G165WC-BCTD"
PART_TYPE"SMLF"
CDS_LMAN_SYM_OUTLINE"-375,1500,375,-1500"
NEEDS_NO_SIZE"TRUE"
CDS_LIB"pure_quanta"
LOCATION"U1"
$SEC"1"
CDS_SEC"1";
"RESET_N \B"
$PN"P1"67;
"DMU_N||DBIU_N \B"
$PN"E2"93;
"DML_N||DBIL_N \B"
$PN"E7"92;
"VSSQ9"
$PN"H9"12;
"VSSQ8"
$PN"H1"12;
"VSSQ7"
$PN"F1"12;
"VSSQ6"
$PN"E8"12;
"VSSQ5"
$PN"E3"12;
"VSSQ4"
$PN"D8"12;
"VSSQ3"
$PN"D2"12;
"VSSQ2"
$PN"C9"12;
"VSSQ1"
$PN"A8"12;
"VSSQ0"
$PN"A2"12;
"VSS8"
$PN"T1"12;
"VSS7"
$PN"N1"12;
"VSS6"
$PN"M9"69;
"VSS5"
$PN"K9"12;
"VSS4"
$PN"K1"12;
"VSS3"
$PN"G8"12;
"VSS2"
$PN"E9"68;
"VSS1"
$PN"E1"12;
"VSS0"
$PN"B2"12;
"VREFCA"
$PN"M1"7;
"PAR"
$PN"T3"51;
"TEN"
$PN"N9"52;
"DQSL_C"
$PN"F3"55;
"DQSL_T"
$PN"G3"56;
"DQSU_C"
$PN"A7"57;
"DQSU_T"
$PN"B7"58;
"CK_C"
$PN"K8"59;
"CK_T"
$PN"K7"60;
"DQU7"
$PN"D7"117;
"DQU6"
$PN"D3"116;
"DQU5"
$PN"C8"115;
"DQU4"
$PN"C2"114;
"DQU3"
$PN"C7"113;
"DQU2"
$PN"C3"112;
"DQU1"
$PN"B8"111;
"DQU0"
$PN"A3"110;
"DQL7"
$PN"J7"109;
"DQL6"
$PN"J3"108;
"DQL5"
$PN"H8"107;
"DQL4"
$PN"H2"106;
"DQL3"
$PN"H7"105;
"DQL2"
$PN"H3"104;
"DQL1"
$PN"F7"103;
"DQL0"
$PN"G2"102;
"ZQ"
$PN"F9"54;
"WE_N||A14 \B"
$PN"L2"71;
"VPP1"
$PN"R9"3;
"VPP0"
$PN"B1"3;
"VDDQ9"
$PN"J8"1;
"VDDQ8"
$PN"J2"1;
"VDDQ7"
$PN"G9"1;
"VDDQ6"
$PN"G1"1;
"VDDQ5"
$PN"F8"1;
"VDDQ4"
$PN"F2"1;
"VDDQ3"
$PN"D9"1;
"VDDQ2"
$PN"C1"1;
"VDDQ1"
$PN"A9"1;
"VDDQ0"
$PN"A1"1;
"VDD9"
$PN"T9"1;
"VDD8"
$PN"R1"1;
"VDD7"
$PN"L9"1;
"VDD6"
$PN"L1"1;
"VDD5"
$PN"J9"1;
"VDD4"
$PN"J1"1;
"VDD3"
$PN"G7"1;
"VDD2"
$PN"D1"1;
"VDD1"
$PN"B9"1;
"VDD0"
$PN"B3"1;
"RAS_N \B"
$PN"L8"90;
"ODT"
$PN"K3"89;
"NC1"
$PN"T7"12;
"CKE"
$PN"K2"72;
"CS_N \B"
$PN"L7"91;
"CAS_N||A15 \B"
$PN"M8"70;
"BG0"
$PN"M2"74;
"BA1"
$PN"N8"76;
"BA0"
$PN"N2"75;
"ALERT_N \B"
$PN"P9"53;
"ACT_N \B"
$PN"L3"73;
"A9"
$PN"R7"101;
"A8"
$PN"R2"100;
"A7"
$PN"R8"99;
"A6"
$PN"P2"96;
"A5"
$PN"P8"65;
"A4"
$PN"N3"66;
"A3"
$PN"N7"64;
"A2"
$PN"R3"63;
"A13"
$PN"T8"94;
"A12||BC_N \B"
$PN"M7"98;
"A11"
$PN"T2"97;
"A10||AP"
$PN"M3"95;
"A1"
$PN"P7"62;
"A0"
$PN"P3"61;
%"Q_CAP"
"1","(-2125,1950)","0","pure_quanta","I197";
;
MATERIAL"X7R"
PACK_TYPE"0402"
VALUE"0.1UF"
TOLERANCE"10%"
VOLTAGE"25V"
SEC_TYPE"0402"
CDS_LIB"pure_quanta"
PART_NUMBER"CH4104K1B00"
LOCATION"C225"
SEC"1";
"B"
$PN"2"15;
"A"
$PN"1"1;
%"Q_CAP"
"1","(-2350,1950)","0","pure_quanta","I198";
;
PACK_TYPE"0402"
VOLTAGE"25V"
TOLERANCE"10%"
MATERIAL"X7R"
VALUE"0.1UF"
SEC_TYPE"0402"
CDS_LIB"pure_quanta"
PART_NUMBER"CH4104K1B00"
LOCATION"C222"
SEC"1";
"B"
$PN"2"15;
"A"
$PN"1"1;
%"Q_CAP"
"1","(-2550,1950)","0","pure_quanta","I199";
;
PACK_TYPE"0402"
MATERIAL"X7R"
TOLERANCE"10%"
VOLTAGE"25V"
VALUE"0.1UF"
SEC_TYPE"0402"
CDS_LIB"pure_quanta"
PART_NUMBER"CH4104K1B00"
LOCATION"C221"
SEC"1";
"B"
$PN"2"15;
"A"
$PN"1"1;
%"UNIVERSAL_GND"
"1","(-2925,950)","0","logical_power","I20";
;
HDL_POWER"GND"
CDS_LIB"logical_power";
"A"16;
%"UNIVERSAL_GND"
"1","(-2550,1700)","0","logical_power","I200";
;
HDL_POWER"GND"
CDS_LIB"logical_power";
"A"15;
%"Q_CAP"
"1","(-2775,1300)","0","pure_quanta","I21";
;
PACK_TYPE"0402"
VOLTAGE"25V"
TOLERANCE"10%"
PART_NUMBER"CH4104K1B00"
MATERIAL"X7R"
VALUE"0.1UF"
CDS_LIB"pure_quanta"
SEC_TYPE"0402"
LOCATION"C8"
SEC"1";
"B"
$PN"2"16;
"A"
$PN"1"3;
%"UNIVERSAL_POWER"
"1","(-3050,1625)","0","logical_power","I22";
;
HDL_POWER"P2V5_AUX"
CDS_LIB"logical_power";
"A"3;
%"Q_CAP"
"1","(-2875,2475)","0","pure_quanta","I23";
;
VOLTAGE"25V"
TOLERANCE"10%"
VALUE"1UF"
MATERIAL"X6S"
PACK_TYPE"C0402"
CDS_LIB"pure_quanta"
SEC_TYPE"C0402"
PART_NUMBER"CH5104KEB02"
LOCATION"C5"
SEC"1";
"B"
$PN"2"14;
"A"
$PN"1"1;
%"Q_CAP"
"1","(-2650,2475)","0","pure_quanta","I24";
;
PACK_TYPE"0402"
VOLTAGE"25V"
TOLERANCE"10%"
VALUE"0.1UF"
MATERIAL"X7R"
PART_NUMBER"CH4104K1B00"
CDS_LIB"pure_quanta"
SEC_TYPE"0402"
LOCATION"C7"
SEC"1";
"B"
$PN"2"14;
"A"
$PN"1"1;
%"Q_CAP"
"1","(-2400,2475)","0","pure_quanta","I25";
;
PART_NUMBER"CH11006JB00"
PACK_TYPE"0402"
MATERIAL"NPO"
TOLERANCE"5%"
VOLTAGE"50V"
VALUE"100PF"
CDS_LIB"pure_quanta"
SEC_TYPE"0402"
LOCATION"C9"
SEC"1";
"B"
$PN"2"14;
"A"
$PN"1"1;
%"Q_RES"
"2","(-250,-75)","0","pure_quanta","I27";
;
WATTAGE"1/16W"
TOLERANCE"1%"
VALUE"1K"
MATERIAL"CHIP"
PART_NUMBER"CS21002FB06"
PACK_TYPE"0402LF"
CDS_LIB"pure_quanta"
LOCATION"R325"
$SEC"1"
CDS_SEC"1";
"A"
$PN"1"8;
"B"
$PN"2"13;
%"Q_RES"
"2","(-250,350)","0","pure_quanta","I28";
;
PACK_TYPE"0402LF"
MATERIAL"CHIP"
WATTAGE"1/16W"
VALUE"1K"
PART_NUMBER"CS21002FB06"
TOLERANCE"1%"
CDS_LIB"pure_quanta"
LOCATION"R324"
$SEC"1"
CDS_SEC"1";
"A"
$PN"1"2;
"B"
$PN"2"8;
%"UNIVERSAL_GND"
"1","(-3600,2050)","0","logical_power","I3";
;
HDL_POWER"GND"
CDS_LIB"logical_power";
"A"14;
%"UNIVERSAL_GND"
"1","(350,-475)","0","logical_power","I31";
;
HDL_POWER"GND"
CDS_LIB"logical_power";
"A"13;
%"Q_CAP"
"1","(150,-75)","0","pure_quanta","I32";
;
PACK_TYPE"0402"
TOLERANCE"10%"
MATERIAL"X7R"
VOLTAGE"25V"
PART_NUMBER"CH4104K1B00"
VALUE"0.1UF"
CDS_LIB"pure_quanta"
LOCATION"C168"
$SEC"1"
CDS_SEC"1";
"B"
$PN"2"13;
"A"
$PN"1"8;
%"Q_CAP"
"1","(550,-75)","0","pure_quanta","I33";
;
VOLTAGE"50V"
PACK_TYPE"C0402"
TOLERANCE"10%"
MATERIAL"X7R"
PART_NUMBER"CH31006KB18"
VALUE"0.01UF"
CDS_LIB"pure_quanta"
LOCATION"C170"
$SEC"1"
CDS_SEC"1";
"B"
$PN"2"13;
"A"
$PN"1"8;
%"Q_CAP"
"1","(475,400)","0","pure_quanta","I34";
;
MATERIAL"EMPTY"
PACK_TYPE"C0402"
PART_NUMBER"CH31006KB18"
VALUE"0.01UF"
VOLTAGE"50V"
TOLERANCE"10%"
CDS_LIB"pure_quanta"
LOCATION"C169"
$SEC"1"
CDS_SEC"1";
"B"
$PN"2"8;
"A"
$PN"1"2;
%"UNIVERSAL_POWER"
"1","(-250,775)","0","logical_power","I35";
;
HDL_POWER"P1V2_AUX"
CDS_LIB"logical_power";
"A"2;
%"UNIVERSAL_GND"
"1","(-275,1325)","0","logical_power","I36";
;
HDL_POWER"GND"
CDS_LIB"logical_power";
"A"12;
%"UNIVERSAL_GND"
"1","(800,2450)","0","logical_power","I39";
;
HDL_POWER"GND"
CDS_LIB"logical_power";
"A"11;
%"Q_CAP"
"1","(-3700,2475)","0","pure_quanta","I4";
;
MATERIAL"X6S"
TOLERANCE"10%"
VOLTAGE"25V"
VALUE"4.7UF"
PART_NUMBER"CH5474KE906"
PACK_TYPE"C0603"
SEC_TYPE"C0603"
CDS_LIB"pure_quanta"
LOCATION"C1"
SEC"1";
"B"
$PN"2"14;
"A"
$PN"1"1;
%"TAP"
"1","(-2025,3200)","2","standard","I41";
;
HDL_TAP"TRUE"
BODY_TYPE"PLUMBING"
CDS_LIB"standard";
"B \NAC \NWC"29;
"S \NAC"
BN"11"97;
%"TAP"
"1","(-2025,3150)","2","standard","I42";
;
HDL_TAP"TRUE"
BODY_TYPE"PLUMBING"
CDS_LIB"standard";
"B \NAC \NWC"29;
"S \NAC"
BN"12"98;
%"TAP"
"1","(-2025,3100)","2","standard","I43";
;
HDL_TAP"TRUE"
BODY_TYPE"PLUMBING"
CDS_LIB"standard";
"B \NAC \NWC"29;
"S \NAC"
BN"13"94;
%"TAP"
"1","(-2025,3250)","2","standard","I44";
;
HDL_TAP"TRUE"
BODY_TYPE"PLUMBING"
CDS_LIB"standard";
"B \NAC \NWC"29;
"S \NAC"
BN"10"95;
%"TAP"
"1","(-2025,3300)","2","standard","I45";
;
HDL_TAP"TRUE"
BODY_TYPE"PLUMBING"
CDS_LIB"standard";
"B \NAC \NWC"29;
"S \NAC"
BN"9"101;
%"TAP"
"1","(-2025,3450)","2","standard","I46";
;
HDL_TAP"TRUE"
BODY_TYPE"PLUMBING"
CDS_LIB"standard";
"B \NAC \NWC"29;
"S \NAC"
BN"6"96;
%"TAP"
"1","(-2025,3400)","2","standard","I47";
;
HDL_TAP"TRUE"
BODY_TYPE"PLUMBING"
CDS_LIB"standard";
"B \NAC \NWC"29;
"S \NAC"
BN"7"99;
%"TAP"
"1","(-2025,3350)","2","standard","I48";
;
HDL_TAP"TRUE"
BODY_TYPE"PLUMBING"
CDS_LIB"standard";
"B \NAC \NWC"29;
"S \NAC"
BN"8"100;
%"Q_CAP"
"1","(-3475,2475)","0","pure_quanta","I5";
;
MATERIAL"X6S"
TOLERANCE"10%"
VOLTAGE"25V"
VALUE"1UF"
PART_NUMBER"CH5104KEB02"
PACK_TYPE"C0402"
CDS_LIB"pure_quanta"
SEC_TYPE"C0402"
LOCATION"C2"
SEC"1";
"B"
$PN"2"14;
"A"
$PN"1"1;
%"TAP"
"1","(-2025,3550)","2","standard","I56";
;
HDL_TAP"TRUE"
BODY_TYPE"PLUMBING"
CDS_LIB"standard";
"B \NAC \NWC"29;
"S \NAC"
BN"4"66;
%"TAP"
"1","(-2025,3500)","2","standard","I57";
;
HDL_TAP"TRUE"
BODY_TYPE"PLUMBING"
CDS_LIB"standard";
"B \NAC \NWC"29;
"S \NAC"
BN"5"65;
%"TAP"
"1","(-2025,3700)","2","standard","I58";
;
HDL_TAP"TRUE"
BODY_TYPE"PLUMBING"
CDS_LIB"standard";
"B \NAC \NWC"29;
"S \NAC"
BN"1"62;
%"TAP"
"1","(-2025,3650)","2","standard","I59";
;
HDL_TAP"TRUE"
BODY_TYPE"PLUMBING"
CDS_LIB"standard";
"B \NAC \NWC"29;
"S \NAC"
BN"2"63;
%"Q_CAP"
"1","(-3275,2475)","0","pure_quanta","I6";
;
VOLTAGE"25V"
VALUE"1UF"
MATERIAL"X6S"
TOLERANCE"10%"
PACK_TYPE"C0402"
CDS_LIB"pure_quanta"
SEC_TYPE"C0402"
PART_NUMBER"CH5104KEB02"
LOCATION"C3"
SEC"1";
"B"
$PN"2"14;
"A"
$PN"1"1;
%"TAP"
"1","(-2025,3600)","2","standard","I60";
;
HDL_TAP"TRUE"
BODY_TYPE"PLUMBING"
CDS_LIB"standard";
"B \NAC \NWC"29;
"S \NAC"
BN"3"64;
%"TAP"
"1","(-2025,3750)","2","standard","I61";
;
HDL_TAP"TRUE"
BODY_TYPE"PLUMBING"
CDS_LIB"standard";
"B \NAC \NWC"29;
"S \NAC"
BN"0"61;
%"TAP"
"1","(50,3750)","0","standard","I62";
;
HDL_TAP"TRUE"
BODY_TYPE"PLUMBING"
CDS_LIB"standard";
"B \NAC \NWC"28;
"S \NAC"
BN"15"117;
%"TAP"
"1","(50,3850)","0","standard","I63";
;
HDL_TAP"TRUE"
BODY_TYPE"PLUMBING"
CDS_LIB"standard";
"B \NAC \NWC"28;
"S \NAC"
BN"13"115;
%"TAP"
"1","(50,3800)","0","standard","I64";
;
HDL_TAP"TRUE"
BODY_TYPE"PLUMBING"
CDS_LIB"standard";
"B \NAC \NWC"28;
"S \NAC"
BN"14"116;
%"TAP"
"1","(50,4000)","0","standard","I65";
;
HDL_TAP"TRUE"
BODY_TYPE"PLUMBING"
CDS_LIB"standard";
"B \NAC \NWC"28;
"S \NAC"
BN"10"112;
%"TAP"
"1","(50,3950)","0","standard","I66";
;
HDL_TAP"TRUE"
BODY_TYPE"PLUMBING"
CDS_LIB"standard";
"B \NAC \NWC"28;
"S \NAC"
BN"11"113;
%"TAP"
"1","(50,3900)","0","standard","I67";
;
HDL_TAP"TRUE"
BODY_TYPE"PLUMBING"
CDS_LIB"standard";
"B \NAC \NWC"28;
"S \NAC"
BN"12"114;
%"TAP"
"1","(50,4100)","0","standard","I68";
;
HDL_TAP"TRUE"
BODY_TYPE"PLUMBING"
CDS_LIB"standard";
"B \NAC \NWC"28;
"S \NAC"
BN"8"110;
%"TAP"
"1","(50,4050)","0","standard","I69";
;
HDL_TAP"TRUE"
BODY_TYPE"PLUMBING"
CDS_LIB"standard";
"B \NAC \NWC"28;
"S \NAC"
BN"9"111;
%"Q_CAP"
"1","(-3075,2475)","0","pure_quanta","I7";
;
VOLTAGE"25V"
TOLERANCE"10%"
VALUE"1UF"
MATERIAL"X6S"
PACK_TYPE"C0402"
CDS_LIB"pure_quanta"
SEC_TYPE"C0402"
PART_NUMBER"CH5104KEB02"
LOCATION"C4"
SEC"1";
"B"
$PN"2"14;
"A"
$PN"1"1;
%"TAP"
"1","(50,4250)","0","standard","I70";
;
HDL_TAP"TRUE"
BODY_TYPE"PLUMBING"
CDS_LIB"standard";
"B \NAC \NWC"28;
"S \NAC"
BN"5"107;
%"TAP"
"1","(50,4200)","0","standard","I71";
;
HDL_TAP"TRUE"
BODY_TYPE"PLUMBING"
CDS_LIB"standard";
"B \NAC \NWC"28;
"S \NAC"
BN"6"108;
%"TAP"
"1","(50,4150)","0","standard","I72";
;
HDL_TAP"TRUE"
BODY_TYPE"PLUMBING"
CDS_LIB"standard";
"B \NAC \NWC"28;
"S \NAC"
BN"7"109;
%"TAP"
"1","(50,4350)","0","standard","I73";
;
HDL_TAP"TRUE"
BODY_TYPE"PLUMBING"
CDS_LIB"standard";
"B \NAC \NWC"28;
"S \NAC"
BN"3"105;
%"TAP"
"1","(50,4300)","0","standard","I74";
;
HDL_TAP"TRUE"
BODY_TYPE"PLUMBING"
CDS_LIB"standard";
"B \NAC \NWC"28;
"S \NAC"
BN"4"106;
%"TAP"
"1","(50,4500)","0","standard","I75";
;
HDL_TAP"TRUE"
BODY_TYPE"PLUMBING"
CDS_LIB"standard";
"B \NAC \NWC"28;
"S \NAC"
BN"0"102;
%"TAP"
"1","(50,4450)","0","standard","I76";
;
HDL_TAP"TRUE"
BODY_TYPE"PLUMBING"
CDS_LIB"standard";
"B \NAC \NWC"28;
"S \NAC"
BN"1"103;
%"TAP"
"1","(50,4400)","0","standard","I77";
;
HDL_TAP"TRUE"
BODY_TYPE"PLUMBING"
CDS_LIB"standard";
"B \NAC \NWC"28;
"S \NAC"
BN"2"104;
%"UNIVERSAL_POWER"
"1","(-3700,2875)","0","logical_power","I8";
;
HDL_POWER"P1V2_AUX"
CDS_LIB"logical_power";
"A"1;
%"Q_CAP"
"1","(800,2650)","0","pure_quanta","I85";
;
PACK_TYPE"0402"
VOLTAGE"25V"
VALUE"0.1UF"
PART_NUMBER"CH4104K1B00"
TOLERANCE"10%"
MATERIAL"X7R"
SEC_TYPE"0402"
CDS_LIB"pure_quanta"
LOCATION"C10"
SEC"1";
"B"
$PN"2"11;
"A"
$PN"1"7;
%"Q_RES"
"1","(2075,-1150)","0","pure_quanta","I89";
;
MATERIAL"CHIP"
VALUE"60.4"
PART_NUMBER"CS06042FB03"
PACK_TYPE"0402LF"
WATTAGE"1/16W"
TOLERANCE"1%"
SEC_TYPE"0402LF"
CDS_LIB"pure_quanta"
LOCATION"R8"
SEC"1";
"B"
$PN"2"33;
"A"
$PN"1"83;
%"Q_RES"
"1","(2075,-950)","0","pure_quanta","I90";
;
MATERIAL"CHIP"
VALUE"60.4"
PART_NUMBER"CS06042FB03"
PACK_TYPE"0402LF"
WATTAGE"1/16W"
TOLERANCE"1%"
SEC_TYPE"0402LF"
CDS_LIB"pure_quanta"
LOCATION"R7"
SEC"1";
"B"
$PN"2"33;
"A"
$PN"1"82;
%"UNIVERSAL_POWER"
"1","(1150,275)","0","logical_power","I91";
;
HDL_POWER"P0V6_DDR_VREF_AUX"
CDS_LIB"logical_power";
"A"8;
%"UNIVERSAL_GND"
"1","(1475,2450)","0","logical_power","I93";
;
HDL_POWER"GND"
CDS_LIB"logical_power";
"A"10;
%"UNIVERSAL_GND"
"1","(2075,2450)","0","logical_power","I94";
;
HDL_POWER"GND"
CDS_LIB"logical_power";
"A"9;
END.
